# TIMECARD (Time Appliance Project (Time Card)) — schematic netlist excerpt (pin names and nets, part order shuffled) for the footprints in the layout excerpt that follows; sources: Cadence DE-HDL packaged netlist, KiCad conversion of R4006-B0001-02_R01.brd

C133  CAPACITOR  0.1UF 10V 10%  pkg SMC_0402R_H022  page 14 : \1\ = XP1R0V_FPGA_VCCINT ; \2\ = SG
R269  RESISTOR  100KOHM 1%  pkg SMC_0402R_H016  page 22 : \1\ = XP3R3V_FPGA ; \2\ = UART_GPS_TX_FPGA_RX

(kicad_pcb
	(version 20260206)
	(generator "pcbnew")
	(generator_version "10.0")
	(general
		(thickness 1.6)
		(legacy_teardrops no)
	)
	(paper "A4")
	(title_block
		(title "timecard-production-celestica-r4006 — R4006-B0001-02_R01.brd")
		(comment 1 "Time Appliance Project (Time Card) / footprints 744-745 of 1113")
	)
	(layers
		(0 "F.Cu" signal "TOP")
		(4 "In1.Cu" signal "L02_GND1")
		(6 "In2.Cu" signal "L03_SIG1")
		(8 "In3.Cu" signal "L04_GND2")
		(10 "In4.Cu" signal "L05_VCC1")
		(12 "In5.Cu" signal "L06_VCC2")
		(14 "In6.Cu" signal "L07_GND3")
		(16 "In7.Cu" signal "L08_SIG2")
		(18 "In8.Cu" signal "L09_GND4")
		(2 "B.Cu" signal "BOTTOM")
		(9 "F.Adhes" user "F.Adhesive")
		(11 "B.Adhes" user "B.Adhesive")
		(13 "F.Paste" user "Package Geometry/Pastemask Top")
		(15 "B.Paste" user "Package Geometry/Pastemask Bottom")
		(5 "F.SilkS" user "Ref Des/Silkscreen Top")
		(7 "B.SilkS" user "Ref Des/Silkscreen Bottom")
		(1 "F.Mask" user "Board Geometry/Soldermask Top")
		(3 "B.Mask" user "Board Geometry/Soldermask Bottom")
		(17 "Dwgs.User" user "User.Drawings")
		(19 "Cmts.User" user "User.Comments")
		(21 "Eco1.User" user "User.Eco1")
		(23 "Eco2.User" user "User.Eco2")
		(25 "Edge.Cuts" user "Board Geometry/Outline")
		(27 "Margin" user)
		(31 "F.CrtYd" user "Package Geometry/Place Bound Top")
		(29 "B.CrtYd" user "Package Geometry/Place Bound Bottom")
		(35 "F.Fab" user "Ref Des/Assembly Top")
		(33 "B.Fab" user "Ref Des/Assembly Bottom")
	)
	(footprint ""
		(layer "B.Cu")
		(at 109.347 -39.878 -90)
		(property "Reference" "C133"
			(at 1.651 41.63695 270)
			(unlocked yes)
			(layer "B.SilkS")
			(effects
				(font
					(size 0.635 0.4064)
					(thickness 0.1524)
				)
				(justify mirror)
			)
		)
		(property "Value" "VAL*"
			(at -0.0762 2.067306 270)
			(unlocked yes)
			(layer "B.Fab")
			(hide yes)
			(effects
				(font
					(size 0.7874 0.5842)
					(thickness 0.1524)
				)
				(justify mirror)
			)
		)
		(property "Device Type" "CAPACITOR-G105-0B104-CK,0.1UF,A"
			(at -0.0508 1.127506 270)
			(unlocked yes)
			(layer "B.Fab")
			(hide yes)
			(effects
				(font
					(size 0.7874 0.5842)
					(thickness 0.1524)
				)
				(justify mirror)
			)
		)
		(property "User Part Number" "PARTNUM*"
			(at -0.1016 4.023106 270)
			(unlocked yes)
			(layer "Cmts.User")
			(hide yes)
			(effects
				(font
					(size 0.7874 0.5842)
					(thickness 0.1524)
				)
				(justify mirror)
			)
		)
		(property "Tolerance" "TOL*"
			(at -0.0762 3.032506 270)
			(unlocked yes)
			(layer "Cmts.User")
			(hide yes)
			(effects
				(font
					(size 0.7874 0.5842)
					(thickness 0.1524)
				)
				(justify mirror)
			)
		)
		(duplicate_pad_numbers_are_jumpers no)
		(fp_line
			(start -1.143 0.5588)
			(end -1.143 -0.5588)
			(stroke
				(width 0.1)
				(type default)
			)
			(layer "B.SilkS")
		)
		(fp_line
			(start 1.143 0.5588)
			(end -1.143 0.5588)
			(stroke
				(width 0.1)
				(type default)
			)
			(layer "B.SilkS")
		)
		(fp_line
			(start -1.143 -0.5588)
			(end 1.143 -0.5588)
			(stroke
				(width 0.1)
				(type default)
			)
			(layer "B.SilkS")
		)
		(fp_line
			(start 1.143 -0.5588)
			(end 1.143 0.5588)
			(stroke
				(width 0.1)
				(type default)
			)
			(layer "B.SilkS")
		)
		(fp_rect
			(start 1.143 0.5588)
			(end -1.143 -0.5588)
			(stroke
				(width 0)
				(type default)
			)
			(fill no)
			(layer "B.CrtYd")
		)
		(fp_line
			(start -0.508 0.3048)
			(end -0.508 -0.3048)
			(stroke
				(width 0.1)
				(type default)
			)
			(layer "B.Fab")
		)
		(fp_line
			(start 0.508 0.3048)
			(end -0.508 0.3048)
			(stroke
				(width 0.1)
				(type default)
			)
			(layer "B.Fab")
		)
		(fp_line
			(start -0.508 -0.3048)
			(end 0.508 -0.3048)
			(stroke
				(width 0.1)
				(type default)
			)
			(layer "B.Fab")
		)
		(fp_line
			(start 0.508 -0.3048)
			(end 0.508 0.3048)
			(stroke
				(width 0.1)
				(type default)
			)
			(layer "B.Fab")
		)
		(pad "1" smd rect
			(at 0.5334 0 90)
			(size 0.7112 0.6096)
			(layers "B.Cu" "B.Mask" "B.Paste")
			(net "XP1R0V_FPGA_VCCINT")
		)
		(pad "2" smd rect
			(at -0.5334 0 90)
			(size 0.7112 0.6096)
			(layers "B.Cu" "B.Mask" "B.Paste")
			(net "SG")
		)
		(zone
			(layer "B.Cu")
			(hatch none 0.5)
			(connect_pads
				(clearance 0)
			)
			(min_thickness 0.25)
			(keepout
				(tracks allowed)
				(vias not_allowed)
				(pads allowed)
				(copperpour not_allowed)
				(footprints allowed)
			)
			(placement
				(enabled no)
				(sheetname "")
			)
			(fill
				(thermal_gap 0.5)
				(thermal_bridge_width 0.5)
				(island_removal_mode 0)
			)
			(polygon
				(pts
					(xy 109.0422 -39.8018) (xy 109.6518 -39.8018) (xy 109.6518 -39.9542) (xy 109.0422 -39.9542)
				)
			)
		)
	)
	(footprint ""
		(layer "B.Cu")
		(at 127.254 -87.757 180)
		(property "Reference" "R269"
			(at -2.794 -0.16637 0)
			(unlocked yes)
			(layer "B.SilkS")
			(effects
				(font
					(size 0.7874 0.5842)
					(thickness 0.1524)
				)
				(justify mirror)
			)
		)
		(property "Value" "VAL*"
			(at -0.02032 2.13233 180)
			(unlocked yes)
			(layer "B.Fab")
			(hide yes)
			(effects
				(font
					(size 0.7874 0.5842)
					(thickness 0.1524)
				)
				(justify mirror)
			)
		)
		(property "Tolerance" "TOL*"
			(at -0.044704 3.05435 180)
			(unlocked yes)
			(layer "Cmts.User")
			(hide yes)
			(effects
				(font
					(size 0.7874 0.5842)
					(thickness 0.1524)
				)
				(justify mirror)
			)
		)
		(property "User Part Number" "PARTNUM*"
			(at -0.02032 4.024884 180)
			(unlocked yes)
			(layer "Cmts.User")
			(hide yes)
			(effects
				(font
					(size 0.7874 0.5842)
					(thickness 0.1524)
				)
				(justify mirror)
			)
		)
		(property "Device Type" "RESISTOR-G155-11003-01,100KOHMA"
			(at -0.008382 1.210564 180)
			(unlocked yes)
			(layer "B.Fab")
			(hide yes)
			(effects
				(font
					(size 0.7874 0.5842)
					(thickness 0.1524)
				)
				(justify mirror)
			)
		)
		(duplicate_pad_numbers_are_jumpers no)
		(fp_line
			(start 1.143 0.5588)
			(end -1.143 0.5588)
			(stroke
				(width 0.1)
				(type default)
			)
			(layer "B.SilkS")
		)
		(fp_line
			(start 1.143 -0.5588)
			(end 1.143 0.5588)
			(stroke
				(width 0.1)
				(type default)
			)
			(layer "B.SilkS")
		)
		(fp_line
			(start -1.143 0.5588)
			(end -1.143 -0.5588)
			(stroke
				(width 0.1)
				(type default)
			)
			(layer "B.SilkS")
		)
		(fp_line
			(start -1.143 -0.5588)
			(end 1.143 -0.5588)
			(stroke
				(width 0.1)
				(type default)
			)
			(layer "B.SilkS")
		)
		(fp_rect
			(start -1.143 -0.5588)
			(end 1.143 0.5588)
			(stroke
				(width 0)
				(type default)
			)
			(fill no)
			(layer "B.CrtYd")
		)
		(fp_line
			(start 0.508 0.3048)
			(end -0.508 0.3048)
			(stroke
				(width 0.1)
				(type default)
			)
			(layer "B.Fab")
		)
		(fp_line
			(start 0.508 -0.3048)
			(end 0.508 0.3048)
			(stroke
				(width 0.1)
				(type default)
			)
			(layer "B.Fab")
		)
		(fp_line
			(start -0.508 0.3048)
			(end -0.508 -0.3048)
			(stroke
				(width 0.1)
				(type default)
			)
			(layer "B.Fab")
		)
		(fp_line
			(start -0.508 -0.3048)
			(end 0.508 -0.3048)
			(stroke
				(width 0.1)
				(type default)
			)
			(layer "B.Fab")
		)
		(pad "1" smd rect
			(at 0.5334 0)
			(size 0.7112 0.6096)
			(layers "B.Cu" "B.Mask" "B.Paste")
			(net "XP3R3V_FPGA")
		)
		(pad "2" smd rect
			(at -0.5334 0)
			(size 0.7112 0.6096)
			(layers "B.Cu" "B.Mask" "B.Paste")
			(net "UART_GPS_TX_FPGA_RX")
		)
		(zone
			(layer "B.Cu")
			(hatch none 0.5)
			(connect_pads
				(clearance 0)
			)
			(min_thickness 0.25)
			(keepout
				(tracks not_allowed)
				(vias allowed)
				(pads allowed)
				(copperpour not_allowed)
				(footprints allowed)
			)
			(placement
				(enabled no)
				(sheetname "")
			)
			(fill
				(thermal_gap 0.5)
				(thermal_bridge_width 0.5)
				(island_removal_mode 0)
			)
			(polygon
				(pts
					(xy 127.3302 -87.4522) (xy 127.3302 -88.0618) (xy 127.1778 -88.0618) (xy 127.1778 -87.4522)
				)
			)
		)
		(zone
			(layer "B.Cu")
			(hatch none 0.5)
			(connect_pads
				(clearance 0)
			)
			(min_thickness 0.25)
			(keepout
				(tracks allowed)
				(vias not_allowed)
				(pads allowed)
				(copperpour not_allowed)
				(footprints allowed)
			)
			(placement
				(enabled no)
				(sheetname "")
			)
			(fill
				(thermal_gap 0.5)
				(thermal_bridge_width 0.5)
				(island_removal_mode 0)
			)
			(polygon
				(pts
					(xy 127.3302 -87.4522) (xy 127.3302 -88.0618) (xy 127.1778 -88.0618) (xy 127.1778 -87.4522)
				)
			)
		)
	)
)
